(kicad_pcb
	(version 20260206)
	(generator "pcbnew")
	(generator_version "10.0")
	(general
		(thickness 1.6)
		(legacy_teardrops no)
	)
	(paper "A4")
	(title_block
		(title "04192023_DAF0TMB3IC0_F0TG_MB_C_brd_V02_OCP.brd")
		(comment 1 "Grand Teton / footprints 3768-3772 of 8354")
	)
	(layers
		(0 "F.Cu" signal "TOP")
		(4 "In1.Cu" signal "GND")
		(6 "In2.Cu" signal "IN1")
		(8 "In3.Cu" signal "GND1")
		(10 "In4.Cu" signal "IN2")
		(12 "In5.Cu" signal "GND2")
		(14 "In6.Cu" signal "IN3")
		(16 "In7.Cu" signal "GND3")
		(18 "In8.Cu" signal "VCC")
		(20 "In9.Cu" signal "VCC1")
		(22 "In10.Cu" signal "GND4")
		(24 "In11.Cu" signal "IN4")
		(26 "In12.Cu" signal "GND5")
		(28 "In13.Cu" signal "IN5")
		(30 "In14.Cu" signal "GND6")
		(32 "In15.Cu" signal "IN6")
		(34 "In16.Cu" signal "GND7")
		(2 "B.Cu" signal "BOTTOM")
		(9 "F.Adhes" user "F.Adhesive")
		(11 "B.Adhes" user "B.Adhesive")
		(13 "F.Paste" user "Package Geometry/Pastemask Top")
		(15 "B.Paste" user "Package Geometry/Pastemask Bottom")
		(5 "F.SilkS" user "Ref Des/Silkscreen Top")
		(7 "B.SilkS" user "Ref Des/Silkscreen Bottom")
		(1 "F.Mask" user "Board Geometry/Soldermask Top")
		(3 "B.Mask" user "Board Geometry/Soldermask Bottom")
		(17 "Dwgs.User" user "User.Drawings")
		(19 "Cmts.User" user "User.Comments")
		(21 "Eco1.User" user "User.Eco1")
		(23 "Eco2.User" user "User.Eco2")
		(25 "Edge.Cuts" user "Board Geometry/Outline")
		(27 "Margin" user)
		(31 "F.CrtYd" user "Package Geometry/Place Bound Top")
		(29 "B.CrtYd" user "Package Geometry/Place Bound Bottom")
		(35 "F.Fab" user "Ref Des/Assembly Top")
		(33 "B.Fab" user "Ref Des/Assembly Bottom")
	)
	(footprint ""
		(layer "F.Cu")
		(at 343.39022 -335.024476)
		(property "Reference" "PU16"
			(at -3.03022 -7.848854 0)
			(unlocked yes)
			(layer "F.SilkS")
			(effects
				(font
					(size 0.7874 0.5842)
					(thickness 0.1524)
				)
				(justify left)
			)
		)
		(property "Value" ""
			(at 0 0 0)
			(layer "F.Fab")
			(effects
				(font
					(size 1.27 1.27)
				)
			)
		)
		(duplicate_pad_numbers_are_jumpers no)
		(fp_line
			(start -2.500122 -2.999994)
			(end -2.24409 -2.999994)
			(stroke
				(width 0.1524)
				(type default)
			)
			(layer "F.SilkS")
		)
		(fp_line
			(start -2.500122 -2.529078)
			(end -2.500122 -2.999994)
			(stroke
				(width 0.1524)
				(type default)
			)
			(layer "F.SilkS")
		)
		(fp_line
			(start -2.500122 0.6604)
			(end -2.500122 0.229108)
			(stroke
				(width 0.1524)
				(type default)
			)
			(layer "F.SilkS")
		)
		(fp_line
			(start -2.500122 2.999994)
			(end -2.500122 2.339594)
			(stroke
				(width 0.1524)
				(type default)
			)
			(layer "F.SilkS")
		)
		(fp_line
			(start -2.2987 2.999994)
			(end -2.500122 2.999994)
			(stroke
				(width 0.1524)
				(type default)
			)
			(layer "F.SilkS")
		)
		(fp_line
			(start 2.31394 -2.999994)
			(end 2.500122 -2.999994)
			(stroke
				(width 0.1524)
				(type default)
			)
			(layer "F.SilkS")
		)
		(fp_line
			(start 2.500122 -2.999994)
			(end 2.500122 -2.44348)
			(stroke
				(width 0.1524)
				(type default)
			)
			(layer "F.SilkS")
		)
		(fp_line
			(start 2.500122 2.339594)
			(end 2.500122 2.999994)
			(stroke
				(width 0.1524)
				(type default)
			)
			(layer "F.SilkS")
		)
		(fp_line
			(start 2.500122 2.999994)
			(end 2.2987 2.999994)
			(stroke
				(width 0.1524)
				(type default)
			)
			(layer "F.SilkS")
		)
		(fp_poly
			(pts
				(xy -2.742692 -2.464308) (xy -3.4163 -2.68859) (xy -2.967228 -3.137662)
			)
			(stroke
				(width 0)
				(type default)
			)
			(fill yes)
			(layer "F.SilkS")
		)
		(fp_line
			(start -2.500122 -2.999994)
			(end 2.500122 -2.999994)
			(stroke
				(width 0.1)
				(type default)
			)
			(layer "F.Fab")
		)
		(fp_line
			(start -2.500122 2.999994)
			(end -2.500122 -2.999994)
			(stroke
				(width 0.1)
				(type default)
			)
			(layer "F.Fab")
		)
		(fp_line
			(start 2.500122 -2.999994)
			(end 2.500122 2.999994)
			(stroke
				(width 0.1)
				(type default)
			)
			(layer "F.Fab")
		)
		(fp_line
			(start 2.500122 2.999994)
			(end -2.500122 2.999994)
			(stroke
				(width 0.1)
				(type default)
			)
			(layer "F.Fab")
		)
		(fp_poly
			(pts
				(xy -4.218432 -2.783078) (xy -4.218432 -1.767078) (xy -3.202432 -2.275078)
			)
			(stroke
				(width 0)
				(type default)
			)
			(fill yes)
			(layer "F.Fab")
		)
		(pad "1" smd rect
			(at -2.400046 -2.275078 90)
			(size 0.2286 0.6096)
			(layers "F.Cu" "F.Mask" "F.Paste")
			(net "PVDDCR_CPU1_P0_VOS5")
		)
		(pad "2" smd rect
			(at -2.400046 -1.82499 90)
			(size 0.2286 0.6096)
			(layers "F.Cu" "F.Mask" "F.Paste")
			(net "GND")
		)
		(pad "3" smd rect
			(at -2.400046 -1.374902 90)
			(size 0.2286 0.6096)
			(layers "F.Cu" "F.Mask" "F.Paste")
			(net "PVDDCR_CPU1_P0_VCC5")
		)
		(pad "4" smd rect
			(at -2.400046 -0.925068 90)
			(size 0.2286 0.6096)
			(layers "F.Cu" "F.Mask" "F.Paste")
			(net "PVDDCR_CPU1_P0_PVCC")
		)
		(pad "5" smd rect
			(at -2.400046 -0.47498 90)
			(size 0.2286 0.6096)
			(layers "F.Cu" "F.Mask" "F.Paste")
			(net "GND")
		)
		(pad "6" smd rect
			(at -2.400046 -0.024892 90)
			(size 0.2286 0.6096)
			(layers "F.Cu" "F.Mask" "F.Paste")
			(net "NC_PVDDCR_CPU1_P0_GL1_5")
		)
		(pad "7_9-20_24" smd circle
			(at 0 1.150112 90)
			(size 0 0)
			(layers "F.Cu" "F.Mask" "F.Paste")
			(net "GND")
		)
		(pad "10_19" smd rect
			(at 0 2.899918 90)
			(size 0.6096 4.318)
			(layers "F.Cu" "F.Mask" "F.Paste")
			(net "SW_PVDDCR_CPU1_P0_SW5")
		)
		(pad "25_29" smd rect
			(at 1.549908 -1.279906 270)
			(size 2.0574 2.3114)
			(layers "F.Cu" "F.Mask" "F.Paste")
			(net "SW_P12V_AUX_PVDDCR_CPU1_P0_FLT")
		)
		(pad "30" smd rect
			(at 2.05994 -2.899918)
			(size 0.2286 0.6096)
			(layers "F.Cu" "F.Mask" "F.Paste")
			(net "SW_P12V_AUX_PVDDCR_CPU1_P0_FLT")
		)
		(pad "31" smd rect
			(at 1.610106 -2.899918)
			(size 0.2286 0.6096)
			(layers "F.Cu" "F.Mask" "F.Paste")
			(net "NC_PVDDCR_CPU1_P0_DNC5")
		)
		(pad "32" smd rect
			(at 1.160018 -2.899918)
			(size 0.2286 0.6096)
			(layers "F.Cu" "F.Mask" "F.Paste")
			(net "SW_PVDDCR_CPU1_P0_BOOTR5")
		)
		(pad "33" smd rect
			(at 0.70993 -2.899918)
			(size 0.2286 0.6096)
			(layers "F.Cu" "F.Mask" "F.Paste")
			(net "SW_PVDDCR_CPU1_P0_BOOT5")
		)
		(pad "34" smd rect
			(at 0.260096 -2.899918)
			(size 0.2286 0.6096)
			(layers "F.Cu" "F.Mask" "F.Paste")
			(net "PVDDCR_CPU1_P0_PWM5")
		)
		(pad "35" smd rect
			(at -0.189992 -2.899918)
			(size 0.2286 0.6096)
			(layers "F.Cu" "F.Mask" "F.Paste")
			(net "PVDDCR_CPU1_P0_VCC5")
		)
		(pad "36" smd rect
			(at -0.64008 -2.899918)
			(size 0.2286 0.6096)
			(layers "F.Cu" "F.Mask" "F.Paste")
			(net "PVDDCR_CPU1_P0_TEMP0")
		)
		(pad "37" smd rect
			(at -1.089914 -2.899918)
			(size 0.2286 0.6096)
			(layers "F.Cu" "F.Mask" "F.Paste")
			(net "PVDDCR_CPU1_P0_LSET5")
		)
		(pad "38" smd rect
			(at -1.540002 -2.899918)
			(size 0.2286 0.6096)
			(layers "F.Cu" "F.Mask" "F.Paste")
			(net "PVDDCR_CPU1_P0_IMON5")
		)
		(pad "39" smd rect
			(at -1.99009 -2.899918)
			(size 0.2286 0.6096)
			(layers "F.Cu" "F.Mask" "F.Paste")
			(net "PVDDCR_CPU1_P0_VCCS")
		)
		(pad "40" smd rect
			(at -0.87503 -1.27508)
			(size 1.7526 1.9558)
			(layers "F.Cu" "F.Mask" "F.Paste")
			(net "GND")
		)
		(pad "41" smd rect
			(at -1.525016 0.249936 270)
			(size 0.3048 0.4572)
			(layers "F.Cu" "F.Mask" "F.Paste")
			(net "NC_PVDDCR_CPU1_P0_GL2_5")
		)
		(zone
			(layer "F.Cu")
			(hatch none 0.5)
			(connect_pads
				(clearance 0)
			)
			(min_thickness 0.25)
			(keepout
				(tracks not_allowed)
				(vias allowed)
				(pads allowed)
				(copperpour not_allowed)
				(footprints allowed)
			)
			(placement
				(enabled no)
				(sheetname "")
			)
			(fill
				(thermal_gap 0.5)
				(thermal_bridge_width 0.5)
				(island_removal_mode 0)
			)
			(polygon
				(pts
					(xy 340.890098 -332.444598) (xy 340.890098 -332.773782) (xy 345.890342 -332.773782) (xy 345.890342 -332.456282)
					(xy 345.60002 -332.456282) (xy 345.60002 -332.480158) (xy 341.18042 -332.480158) (xy 341.18042 -332.444598)
				)
			)
		)
		(zone
			(layer "F.Cu")
			(hatch none 0.5)
			(connect_pads
				(clearance 0)
			)
			(min_thickness 0.25)
			(keepout
				(tracks not_allowed)
				(vias allowed)
				(pads allowed)
				(copperpour not_allowed)
				(footprints allowed)
			)
			(placement
				(enabled no)
				(sheetname "")
			)
			(fill
				(thermal_gap 0.5)
				(thermal_bridge_width 0.5)
				(island_removal_mode 0)
			)
			(polygon
				(pts
					(xy 343.44229 -335.270856) (xy 343.44229 -337.328256) (xy 341.58809 -337.328256) (xy 341.58809 -337.08721)
					(xy 341.345774 -337.08721) (xy 341.345774 -337.568794) (xy 345.109038 -337.568794) (xy 345.109038 -337.383882)
					(xy 343.733628 -337.383882) (xy 343.733628 -335.224882) (xy 345.890342 -335.224882) (xy 345.890342 -334.9752)
					(xy 343.737946 -334.9752)
				)
			)
		)
	)
	(footprint ""
		(layer "F.Cu")
		(at 320.612262 -403.1615 -90)
		(property "Reference" "R6809"
			(at 0 0 270)
			(layer "F.SilkS")
			(hide yes)
			(effects
				(font
					(size 1.27 1.27)
				)
			)
		)
		(property "Value" ""
			(at 0 0 270)
			(layer "F.Fab")
			(effects
				(font
					(size 1.27 1.27)
				)
			)
		)
		(duplicate_pad_numbers_are_jumpers no)
		(fp_line
			(start -0.32512 0.175006)
			(end -0.32512 -0.175006)
			(stroke
				(width 0.1)
				(type default)
			)
			(layer "F.Fab")
		)
		(fp_line
			(start 0.32512 0.175006)
			(end -0.32512 0.175006)
			(stroke
				(width 0.1)
				(type default)
			)
			(layer "F.Fab")
		)
		(fp_line
			(start -0.32512 -0.175006)
			(end 0.32512 -0.175006)
			(stroke
				(width 0.1)
				(type default)
			)
			(layer "F.Fab")
		)
		(fp_line
			(start 0.32512 -0.175006)
			(end 0.32512 0.175006)
			(stroke
				(width 0.1)
				(type default)
			)
			(layer "F.Fab")
		)
		(pad "1" smd rect
			(at -0.2667 0 270)
			(size 0.3048 0.381)
			(layers "F.Cu" "F.Mask" "F.Paste")
			(net "RT_CPU0_P0_VQPS")
		)
		(pad "2" smd rect
			(at 0.2667 0 90)
			(size 0.3048 0.381)
			(layers "F.Cu" "F.Mask" "F.Paste")
			(net "GND")
		)
	)
	(footprint ""
		(layer "F.Cu")
		(at 367.441226 -62.0903)
		(property "Reference" "R8023"
			(at 0 0 0)
			(layer "F.SilkS")
			(hide yes)
			(effects
				(font
					(size 1.27 1.27)
				)
			)
		)
		(property "Value" ""
			(at 0 0 0)
			(layer "F.Fab")
			(effects
				(font
					(size 1.27 1.27)
				)
			)
		)
		(duplicate_pad_numbers_are_jumpers no)
		(fp_line
			(start -0.7874 -0.4064)
			(end 0.7874 -0.4064)
			(stroke
				(width 0.1524)
				(type default)
			)
			(layer "F.SilkS")
		)
		(fp_line
			(start -0.7874 0.4064)
			(end -0.7874 -0.4064)
			(stroke
				(width 0.1524)
				(type default)
			)
			(layer "F.SilkS")
		)
		(fp_line
			(start 0.7874 -0.4064)
			(end 0.7874 0.4064)
			(stroke
				(width 0.1524)
				(type default)
			)
			(layer "F.SilkS")
		)
		(fp_line
			(start 0.7874 0.4064)
			(end -0.7874 0.4064)
			(stroke
				(width 0.1524)
				(type default)
			)
			(layer "F.SilkS")
		)
		(fp_line
			(start -0.67945 -0.305054)
			(end -0.12065 -0.305054)
			(stroke
				(width 0.1)
				(type default)
			)
			(layer "F.Fab")
		)
		(fp_line
			(start -0.67945 0.3048)
			(end -0.67945 -0.305054)
			(stroke
				(width 0.1)
				(type default)
			)
			(layer "F.Fab")
		)
		(fp_line
			(start -0.12065 -0.305054)
			(end -0.12065 -0.2794)
			(stroke
				(width 0.1)
				(type default)
			)
			(layer "F.Fab")
		)
		(fp_line
			(start -0.12065 -0.2794)
			(end 0.12065 -0.2794)
			(stroke
				(width 0.1)
				(type default)
			)
			(layer "F.Fab")
		)
		(fp_line
			(start -0.12065 0.2794)
			(end -0.12065 0.3048)
			(stroke
				(width 0.1)
				(type default)
			)
			(layer "F.Fab")
		)
		(fp_line
			(start -0.12065 0.3048)
			(end -0.67945 0.3048)
			(stroke
				(width 0.1)
				(type default)
			)
			(layer "F.Fab")
		)
		(fp_line
			(start 0.120396 0.2794)
			(end -0.12065 0.2794)
			(stroke
				(width 0.1)
				(type default)
			)
			(layer "F.Fab")
		)
		(fp_line
			(start 0.120396 0.3048)
			(end 0.120396 0.2794)
			(stroke
				(width 0.1)
				(type default)
			)
			(layer "F.Fab")
		)
		(fp_line
			(start 0.12065 -0.3048)
			(end 0.67945 -0.3048)
			(stroke
				(width 0.1)
				(type default)
			)
			(layer "F.Fab")
		)
		(fp_line
			(start 0.12065 -0.2794)
			(end 0.12065 -0.3048)
			(stroke
				(width 0.1)
				(type default)
			)
			(layer "F.Fab")
		)
		(fp_line
			(start 0.67945 -0.3048)
			(end 0.67945 0.3048)
			(stroke
				(width 0.1)
				(type default)
			)
			(layer "F.Fab")
		)
		(fp_line
			(start 0.67945 0.3048)
			(end 0.120396 0.3048)
			(stroke
				(width 0.1)
				(type default)
			)
			(layer "F.Fab")
		)
		(pad "1" smd circle
			(at -0.40005 0)
			(size 0 0)
			(layers "F.Cu" "F.Mask" "F.Paste")
			(net "LED_P12V_AUX_R2")
		)
		(pad "2" smd circle
			(at 0.40005 0)
			(size 0 0)
			(layers "F.Cu" "F.Mask" "F.Paste")
			(net "LED_P12V_AUX_R3")
		)
	)
	(footprint ""
		(layer "F.Cu")
		(at 288.198052 -14.354048)
		(property "Reference" "R4179"
			(at 0 0 0)
			(layer "F.SilkS")
			(hide yes)
			(effects
				(font
					(size 1.27 1.27)
				)
			)
		)
		(property "Value" ""
			(at 0 0 0)
			(layer "F.Fab")
			(effects
				(font
					(size 1.27 1.27)
				)
			)
		)
		(duplicate_pad_numbers_are_jumpers no)
		(fp_line
			(start -0.7874 -0.4064)
			(end 0.7874 -0.4064)
			(stroke
				(width 0.1524)
				(type default)
			)
			(layer "F.SilkS")
		)
		(fp_line
			(start -0.7874 0.4064)
			(end -0.7874 -0.4064)
			(stroke
				(width 0.1524)
				(type default)
			)
			(layer "F.SilkS")
		)
		(fp_line
			(start 0.7874 -0.4064)
			(end 0.7874 0.4064)
			(stroke
				(width 0.1524)
				(type default)
			)
			(layer "F.SilkS")
		)
		(fp_line
			(start 0.7874 0.4064)
			(end -0.7874 0.4064)
			(stroke
				(width 0.1524)
				(type default)
			)
			(layer "F.SilkS")
		)
		(fp_line
			(start -0.67945 -0.305054)
			(end -0.12065 -0.305054)
			(stroke
				(width 0.1)
				(type default)
			)
			(layer "F.Fab")
		)
		(fp_line
			(start -0.67945 0.3048)
			(end -0.67945 -0.305054)
			(stroke
				(width 0.1)
				(type default)
			)
			(layer "F.Fab")
		)
		(fp_line
			(start -0.12065 -0.305054)
			(end -0.12065 -0.2794)
			(stroke
				(width 0.1)
				(type default)
			)
			(layer "F.Fab")
		)
		(fp_line
			(start -0.12065 -0.2794)
			(end 0.12065 -0.2794)
			(stroke
				(width 0.1)
				(type default)
			)
			(layer "F.Fab")
		)
		(fp_line
			(start -0.12065 0.2794)
			(end -0.12065 0.3048)
			(stroke
				(width 0.1)
				(type default)
			)
			(layer "F.Fab")
		)
		(fp_line
			(start -0.12065 0.3048)
			(end -0.67945 0.3048)
			(stroke
				(width 0.1)
				(type default)
			)
			(layer "F.Fab")
		)
		(fp_line
			(start 0.120396 0.2794)
			(end -0.12065 0.2794)
			(stroke
				(width 0.1)
				(type default)
			)
			(layer "F.Fab")
		)
		(fp_line
			(start 0.120396 0.3048)
			(end 0.120396 0.2794)
			(stroke
				(width 0.1)
				(type default)
			)
			(layer "F.Fab")
		)
		(fp_line
			(start 0.12065 -0.3048)
			(end 0.67945 -0.3048)
			(stroke
				(width 0.1)
				(type default)
			)
			(layer "F.Fab")
		)
		(fp_line
			(start 0.12065 -0.2794)
			(end 0.12065 -0.3048)
			(stroke
				(width 0.1)
				(type default)
			)
			(layer "F.Fab")
		)
		(fp_line
			(start 0.67945 -0.3048)
			(end 0.67945 0.3048)
			(stroke
				(width 0.1)
				(type default)
			)
			(layer "F.Fab")
		)
		(fp_line
			(start 0.67945 0.3048)
			(end 0.120396 0.3048)
			(stroke
				(width 0.1)
				(type default)
			)
			(layer "F.Fab")
		)
		(pad "1" smd circle
			(at -0.40005 0)
			(size 0 0)
			(layers "F.Cu" "F.Mask" "F.Paste")
			(net "SMB_LM75_1_3V3AUX_SCL")
		)
		(pad "2" smd circle
			(at 0.40005 0)
			(size 0 0)
			(layers "F.Cu" "F.Mask" "F.Paste")
			(net "SMB_LM75_1_3V3AUX_SCL_R1")
		)
	)
	(footprint ""
		(layer "F.Cu")
		(at 97.177352 -71.21398)
		(property "Reference" "PC1322"
			(at 0 0 0)
			(layer "F.SilkS")
			(hide yes)
			(effects
				(font
					(size 1.27 1.27)
				)
			)
		)
		(property "Value" ""
			(at 0 0 0)
			(layer "F.Fab")
			(effects
				(font
					(size 1.27 1.27)
				)
			)
		)
		(duplicate_pad_numbers_are_jumpers no)
		(fp_line
			(start -0.7874 -0.4064)
			(end 0.7874 -0.4064)
			(stroke
				(width 0.1524)
				(type default)
			)
			(layer "F.SilkS")
		)
		(fp_line
			(start -0.7874 0.4064)
			(end -0.7874 -0.4064)
			(stroke
				(width 0.1524)
				(type default)
			)
			(layer "F.SilkS")
		)
		(fp_line
			(start 0.7874 -0.4064)
			(end 0.7874 0.4064)
			(stroke
				(width 0.1524)
				(type default)
			)
			(layer "F.SilkS")
		)
		(fp_line
			(start 0.7874 0.4064)
			(end -0.7874 0.4064)
			(stroke
				(width 0.1524)
				(type default)
			)
			(layer "F.SilkS")
		)
		(fp_line
			(start -0.67945 -0.305054)
			(end -0.12065 -0.305054)
			(stroke
				(width 0.1)
				(type default)
			)
			(layer "F.Fab")
		)
		(fp_line
			(start -0.67945 0.3048)
			(end -0.67945 -0.305054)
			(stroke
				(width 0.1)
				(type default)
			)
			(layer "F.Fab")
		)
		(fp_line
			(start -0.12065 -0.305054)
			(end -0.12065 -0.2794)
			(stroke
				(width 0.1)
				(type default)
			)
			(layer "F.Fab")
		)
		(fp_line
			(start -0.12065 -0.2794)
			(end 0.12065 -0.2794)
			(stroke
				(width 0.1)
				(type default)
			)
			(layer "F.Fab")
		)
		(fp_line
			(start -0.12065 0.2794)
			(end -0.12065 0.3048)
			(stroke
				(width 0.1)
				(type default)
			)
			(layer "F.Fab")
		)
		(fp_line
			(start -0.12065 0.3048)
			(end -0.67945 0.3048)
			(stroke
				(width 0.1)
				(type default)
			)
			(layer "F.Fab")
		)
		(fp_line
			(start 0.120396 0.2794)
			(end -0.12065 0.2794)
			(stroke
				(width 0.1)
				(type default)
			)
			(layer "F.Fab")
		)
		(fp_line
			(start 0.120396 0.3048)
			(end 0.120396 0.2794)
			(stroke
				(width 0.1)
				(type default)
			)
			(layer "F.Fab")
		)
		(fp_line
			(start 0.12065 -0.3048)
			(end 0.67945 -0.3048)
			(stroke
				(width 0.1)
				(type default)
			)
			(layer "F.Fab")
		)
		(fp_line
			(start 0.12065 -0.2794)
			(end 0.12065 -0.3048)
			(stroke
				(width 0.1)
				(type default)
			)
			(layer "F.Fab")
		)
		(fp_line
			(start 0.67945 -0.3048)
			(end 0.67945 0.3048)
			(stroke
				(width 0.1)
				(type default)
			)
			(layer "F.Fab")
		)
		(fp_line
			(start 0.67945 0.3048)
			(end 0.120396 0.3048)
			(stroke
				(width 0.1)
				(type default)
			)
			(layer "F.Fab")
		)
		(pad "1" smd circle
			(at -0.40005 0)
			(size 0 0)
			(layers "F.Cu" "F.Mask" "F.Paste")
			(net "P3V3_OCP_GATE_PU207_2")
		)
		(pad "2" smd circle
			(at 0.40005 0)
			(size 0 0)
			(layers "F.Cu" "F.Mask" "F.Paste")
			(net "GND")
		)
	)
)
